(kicad_pcb
	(version 20260206)
	(generator "pcbnew")
	(generator_version "10.0")
	(general
		(thickness 1.6)
		(legacy_teardrops no)
	)
	(paper "A4")
	(title_block
		(title "baseboard — 13948-1b.1110WZS1818.brd")
		(comment 1 "Honey Badger (Wiwynn) / footprints 1284-1290 of 2523")
	)
	(layers
		(0 "F.Cu" signal "TOP")
		(4 "In1.Cu" signal "L2GND")
		(6 "In2.Cu" signal "L3")
		(8 "In3.Cu" signal "L4VCC")
		(10 "In4.Cu" signal "L5VCC")
		(12 "In5.Cu" signal "L6")
		(14 "In6.Cu" signal "L7GND")
		(2 "B.Cu" signal "BOTTOM")
		(9 "F.Adhes" user "F.Adhesive")
		(11 "B.Adhes" user "B.Adhesive")
		(13 "F.Paste" user "Package Geometry/Pastemask Top")
		(15 "B.Paste" user "Package Geometry/Pastemask Bottom")
		(5 "F.SilkS" user "Ref Des/Silkscreen Top")
		(7 "B.SilkS" user "Ref Des/Silkscreen Bottom")
		(1 "F.Mask" user "Board Geometry/Soldermask Top")
		(3 "B.Mask" user "Board Geometry/Soldermask Bottom")
		(17 "Dwgs.User" user "User.Drawings")
		(19 "Cmts.User" user "User.Comments")
		(21 "Eco1.User" user "User.Eco1")
		(23 "Eco2.User" user "User.Eco2")
		(25 "Edge.Cuts" user "Board Geometry/Outline")
		(27 "Margin" user)
		(31 "F.CrtYd" user "Package Geometry/Place Bound Top")
		(29 "B.CrtYd" user "Package Geometry/Place Bound Bottom")
		(35 "F.Fab" user "Ref Des/Assembly Top")
		(33 "B.Fab" user "Ref Des/Assembly Bottom")
	)
	(footprint ""
		(layer "F.Cu")
		(at 110.63097 -114.3 180)
		(property "Reference" "SC1080"
			(at 0 0 180)
			(layer "F.SilkS")
			(hide yes)
			(effects
				(font
					(size 1.27 1.27)
				)
			)
		)
		(property "Value" "SCD01U10V1KX-GP"
			(at -2.8321 -1.7399 180)
			(unlocked yes)
			(layer "F.Fab")
			(hide yes)
			(effects
				(font
					(size 1.016 1.016)
					(thickness 0.1524)
				)
			)
		)
		(property "Device Type" "C0201H13"
			(at -2.8321 -3.2639 180)
			(unlocked yes)
			(layer "F.Fab")
			(hide yes)
			(effects
				(font
					(size 1.016 1.016)
					(thickness 0.1524)
				)
			)
		)
		(duplicate_pad_numbers_are_jumpers no)
		(fp_rect
			(start -0.2794 0.6477)
			(end 0.2794 -0.6477)
			(stroke
				(width 0)
				(type default)
			)
			(fill no)
			(layer "F.CrtYd")
		)
		(fp_rect
			(start -0.2794 0.6477)
			(end 0.2794 -0.6477)
			(stroke
				(width 0)
				(type default)
			)
			(fill no)
			(layer "F.Fab")
		)
		(pad "1" smd custom
			(at 0 -0.2794 180)
			(size 0.0762 0.0762)
			(layers "F.Cu" "F.Mask" "F.Paste")
			(net "SAS_HDD_TX6_N")
			(options
				(clearance outline)
				(anchor circle)
			)
			(primitives
				(gr_poly
					(pts
						(arc
							(start 0.1524 -0.127)
							(mid 0.137521 -0.162921)
							(end 0.1016 -0.1778)
						)
						(arc
							(start -0.1016 -0.1778)
							(mid -0.137521 -0.162921)
							(end -0.1524 -0.127)
						)
						(arc
							(start -0.1524 0.127)
							(mid -0.137521 0.162921)
							(end -0.1016 0.1778)
						)
						(arc
							(start 0.1016 0.1778)
							(mid 0.137521 0.162921)
							(end 0.1524 0.127)
						)
					)
					(width 0)
					(fill yes)
				)
			)
		)
		(pad "2" smd custom
			(at 0 0.2794 180)
			(size 0.0762 0.0762)
			(layers "F.Cu" "F.Mask" "F.Paste")
			(net "SAS_EXP_GF_TX_DN10")
			(options
				(clearance outline)
				(anchor circle)
			)
			(primitives
				(gr_poly
					(pts
						(arc
							(start 0.1524 -0.127)
							(mid 0.137521 -0.162921)
							(end 0.1016 -0.1778)
						)
						(arc
							(start -0.1016 -0.1778)
							(mid -0.137521 -0.162921)
							(end -0.1524 -0.127)
						)
						(arc
							(start -0.1524 0.127)
							(mid -0.137521 0.162921)
							(end -0.1016 0.1778)
						)
						(arc
							(start 0.1016 0.1778)
							(mid 0.137521 0.162921)
							(end 0.1524 0.127)
						)
					)
					(width 0)
					(fill yes)
				)
			)
		)
	)
	(footprint ""
		(layer "F.Cu")
		(at 204.089 -217.424 90)
		(property "Reference" "C42"
			(at 0 0 90)
			(layer "F.SilkS")
			(hide yes)
			(effects
				(font
					(size 1.27 1.27)
				)
			)
		)
		(property "Value" "SCD1U16V2KX-3GP"
			(at 1.1811 -2.7051 90)
			(unlocked yes)
			(layer "F.Fab")
			(hide yes)
			(effects
				(font
					(size 1.016 1.016)
					(thickness 0.1524)
				)
			)
		)
		(property "Device Type" "C402H22"
			(at 1.1811 -4.2291 90)
			(unlocked yes)
			(layer "F.Fab")
			(hide yes)
			(effects
				(font
					(size 1.016 1.016)
					(thickness 0.1524)
				)
			)
		)
		(duplicate_pad_numbers_are_jumpers no)
		(fp_rect
			(start -0.4318 0.9525)
			(end 0.4318 -0.9525)
			(stroke
				(width 0)
				(type default)
			)
			(fill no)
			(layer "F.CrtYd")
		)
		(fp_rect
			(start -0.4318 0.9525)
			(end 0.4318 -0.9525)
			(stroke
				(width 0)
				(type default)
			)
			(fill no)
			(layer "F.Fab")
		)
		(pad "1" smd custom
			(at 0 -0.4445 90)
			(size 0.1524 0.1524)
			(layers "F.Cu" "F.Mask" "F.Paste")
			(net "P3V3_STBY")
			(options
				(clearance outline)
				(anchor circle)
			)
			(primitives
				(gr_poly
					(pts
						(arc
							(start 0.3048 -0.2032)
							(mid 0.275042 -0.275042)
							(end 0.2032 -0.3048)
						)
						(arc
							(start -0.2032 -0.3048)
							(mid -0.275042 -0.275042)
							(end -0.3048 -0.2032)
						)
						(arc
							(start -0.3048 0.2032)
							(mid -0.275042 0.275042)
							(end -0.2032 0.3048)
						)
						(arc
							(start 0.2032 0.3048)
							(mid 0.275042 0.275042)
							(end 0.3048 0.2032)
						)
					)
					(width 0)
					(fill yes)
				)
			)
		)
		(pad "2" smd custom
			(at 0 0.4445 90)
			(size 0.1524 0.1524)
			(layers "F.Cu" "F.Mask" "F.Paste")
			(net "GND")
			(options
				(clearance outline)
				(anchor circle)
			)
			(primitives
				(gr_poly
					(pts
						(arc
							(start 0.3048 -0.2032)
							(mid 0.275042 -0.275042)
							(end 0.2032 -0.3048)
						)
						(arc
							(start -0.2032 -0.3048)
							(mid -0.275042 -0.275042)
							(end -0.3048 -0.2032)
						)
						(arc
							(start -0.3048 0.2032)
							(mid -0.275042 0.275042)
							(end -0.2032 0.3048)
						)
						(arc
							(start 0.2032 0.3048)
							(mid 0.275042 0.275042)
							(end 0.3048 0.2032)
						)
					)
					(width 0)
					(fill yes)
				)
			)
		)
	)
	(footprint ""
		(layer "F.Cu")
		(at 144.126966 -40.513)
		(property "Reference" "STP119"
			(at 0 0 0)
			(layer "F.SilkS")
			(hide yes)
			(effects
				(font
					(size 1.27 1.27)
				)
			)
		)
		(property "Value" "TPAD28"
			(at 0.0127 -1.8034 0)
			(unlocked yes)
			(layer "F.Fab")
			(hide yes)
			(effects
				(font
					(size 1.016 1.016)
					(thickness 0.1524)
				)
			)
		)
		(property "Device Type" "TPAD28"
			(at 0.0127 -3.3274 0)
			(unlocked yes)
			(layer "F.Fab")
			(hide yes)
			(effects
				(font
					(size 1.016 1.016)
					(thickness 0.1524)
				)
			)
		)
		(duplicate_pad_numbers_are_jumpers no)
		(fp_poly
			(pts
				(arc
					(start 0.3556 0)
					(mid -0.3556 0)
					(end 0.3556 0)
				)
			)
			(stroke
				(width 0)
				(type default)
			)
			(fill no)
			(layer "F.CrtYd")
		)
		(fp_poly
			(pts
				(arc
					(start 0.6096 0)
					(mid -0.6096 0)
					(end 0.6096 0)
				)
			)
			(stroke
				(width 0)
				(type default)
			)
			(fill no)
			(layer "F.Fab")
		)
		(pad "1" smd circle
			(at 0 0)
			(size 0.7112 0.7112)
			(layers "F.Cu" "F.Mask" "F.Paste")
			(net "XM_ADDR_19")
		)
	)
	(footprint ""
		(layer "F.Cu")
		(at 187.006992 -38.227)
		(property "Reference" "R372"
			(at 0 0 0)
			(layer "F.SilkS")
			(hide yes)
			(effects
				(font
					(size 1.27 1.27)
				)
			)
		)
		(property "Value" "0R2J-2-GP"
			(at 0.064008 -3.993896 0)
			(unlocked yes)
			(layer "F.Fab")
			(hide yes)
			(effects
				(font
					(size 1.016 1.016)
					(thickness 0.1524)
				)
			)
		)
		(property "Device Type" "R402H16"
			(at 0.064008 -5.517896 0)
			(unlocked yes)
			(layer "F.Fab")
			(hide yes)
			(effects
				(font
					(size 1.016 1.016)
					(thickness 0.1524)
				)
			)
		)
		(duplicate_pad_numbers_are_jumpers no)
		(fp_line
			(start -0.508 -0.9398)
			(end -0.508 0.9398)
			(stroke
				(width 0.1524)
				(type default)
			)
			(layer "F.SilkS")
		)
		(fp_line
			(start 0.508 -0.9398)
			(end -0.508 -0.9398)
			(stroke
				(width 0.1524)
				(type default)
			)
			(layer "F.SilkS")
		)
		(fp_rect
			(start -0.508 0.9398)
			(end 0.508 -0.9398)
			(stroke
				(width 0)
				(type default)
			)
			(fill no)
			(layer "F.CrtYd")
		)
		(fp_rect
			(start -0.508 0.9398)
			(end 0.508 -0.9398)
			(stroke
				(width 0)
				(type default)
			)
			(fill no)
			(layer "F.Fab")
		)
		(pad "1" smd custom
			(at 0 -0.4445)
			(size 0.1397 0.1397)
			(layers "F.Cu" "F.Mask" "F.Paste")
			(net "FM_BMC_RESET_N")
			(options
				(clearance outline)
				(anchor circle)
			)
			(primitives
				(gr_poly
					(pts
						(arc
							(start -0.1778 -0.2794)
							(mid -0.249642 -0.249642)
							(end -0.2794 -0.1778)
						)
						(arc
							(start -0.2794 0.1778)
							(mid -0.249642 0.249642)
							(end -0.1778 0.2794)
						)
						(arc
							(start 0.1778 0.2794)
							(mid 0.249642 0.249642)
							(end 0.2794 0.1778)
						)
						(arc
							(start 0.2794 -0.1778)
							(mid 0.249642 -0.249642)
							(end 0.1778 -0.2794)
						)
					)
					(width 0)
					(fill yes)
				)
			)
		)
		(pad "2" smd custom
			(at 0 0.4445)
			(size 0.1397 0.1397)
			(layers "F.Cu" "F.Mask" "F.Paste")
			(net "PHY_RESET#")
			(options
				(clearance outline)
				(anchor circle)
			)
			(primitives
				(gr_poly
					(pts
						(arc
							(start -0.1778 -0.2794)
							(mid -0.249642 -0.249642)
							(end -0.2794 -0.1778)
						)
						(arc
							(start -0.2794 0.1778)
							(mid -0.249642 0.249642)
							(end -0.1778 0.2794)
						)
						(arc
							(start 0.1778 0.2794)
							(mid 0.249642 0.249642)
							(end 0.2794 0.1778)
						)
						(arc
							(start 0.2794 -0.1778)
							(mid 0.249642 -0.249642)
							(end 0.1778 -0.2794)
						)
					)
					(width 0)
					(fill yes)
				)
			)
		)
	)
	(footprint ""
		(layer "F.Cu")
		(at 57.785 -231.267 -90)
		(property "Reference" "R9020"
			(at 0 0 270)
			(layer "F.SilkS")
			(hide yes)
			(effects
				(font
					(size 1.27 1.27)
				)
			)
		)
		(property "Value" "D002RL3115F-L-GP"
			(at 3.2258 1.2954 270)
			(unlocked yes)
			(layer "F.Fab")
			(hide yes)
			(effects
				(font
					(size 1.016 1.016)
					(thickness 0.1524)
				)
			)
		)
		(property "Device Type" "RL3115-4PH45"
			(at 3.2258 -0.2286 270)
			(unlocked yes)
			(layer "F.Fab")
			(hide yes)
			(effects
				(font
					(size 1.016 1.016)
					(thickness 0.1524)
				)
			)
		)
		(duplicate_pad_numbers_are_jumpers no)
		(fp_line
			(start -1.9685 1.651)
			(end -1.9685 -1.651)
			(stroke
				(width 0.1524)
				(type default)
			)
			(layer "F.SilkS")
		)
		(fp_line
			(start 1.9685 1.651)
			(end -1.9685 1.651)
			(stroke
				(width 0.1524)
				(type default)
			)
			(layer "F.SilkS")
		)
		(fp_line
			(start -1.9685 -1.651)
			(end 1.9685 -1.651)
			(stroke
				(width 0.1524)
				(type default)
			)
			(layer "F.SilkS")
		)
		(fp_line
			(start 1.9685 -1.651)
			(end 1.9685 1.651)
			(stroke
				(width 0.1524)
				(type default)
			)
			(layer "F.SilkS")
		)
		(fp_line
			(start -2.0574 -1.7653)
			(end -2.0574 -0.4064)
			(stroke
				(width 0.3302)
				(type default)
			)
			(layer "F.SilkS")
		)
		(fp_line
			(start -0.5334 -1.7653)
			(end -2.0574 -1.7653)
			(stroke
				(width 0.3302)
				(type default)
			)
			(layer "F.SilkS")
		)
		(fp_poly
			(pts
				(xy -0.561594 -1.726946) (xy -0.053594 -2.234946) (xy -1.069594 -2.234946)
			)
			(stroke
				(width 0)
				(type default)
			)
			(fill yes)
			(layer "F.SilkS")
		)
		(fp_rect
			(start -1.524 0.7493)
			(end 1.524 -0.7493)
			(stroke
				(width 0)
				(type default)
			)
			(fill no)
			(layer "F.CrtYd")
		)
		(fp_poly
			(pts
				(xy -2.2225 1.905) (xy -2.2225 -1.905) (xy 2.2225 -1.905) (xy 2.2225 -0.7493) (xy -1.524 -0.7493)
				(xy -1.524 0.7493) (xy 1.524 0.7493) (xy 1.524 -0.7366) (xy 2.2225 -0.7366) (xy 2.2225 1.905)
			)
			(stroke
				(width 0)
				(type default)
			)
			(fill no)
			(layer "F.CrtYd")
		)
		(fp_rect
			(start -2.2225 1.905)
			(end 2.2225 -1.905)
			(stroke
				(width 0)
				(type default)
			)
			(fill no)
			(layer "F.Fab")
		)
		(pad "1" smd rect
			(at -0.5715 -0.813562 270)
			(size 2.286 1.143)
			(layers "F.Cu" "F.Mask" "F.Paste")
			(net "MB0_P12V_MAIN_R")
		)
		(pad "2" smd rect
			(at -0.5715 0.813562 270)
			(size 2.286 1.143)
			(layers "F.Cu" "F.Mask" "F.Paste")
			(net "P12V_PCIE")
		)
		(pad "3" smd rect
			(at 1.334008 -0.813562 270)
			(size 0.762 1.143)
			(layers "F.Cu" "F.Mask" "F.Paste")
			(net "MB0_CM_SENSE_R1_N")
		)
		(pad "4" smd rect
			(at 1.334008 0.813562 270)
			(size 0.762 1.143)
			(layers "F.Cu" "F.Mask" "F.Paste")
			(net "MB0_CM_SENSE_R1_P")
		)
		(zone
			(layer "F.Cu")
			(hatch none 0.5)
			(connect_pads
				(clearance 0)
			)
			(min_thickness 0.25)
			(keepout
				(tracks allowed)
				(vias not_allowed)
				(pads allowed)
				(copperpour not_allowed)
				(footprints allowed)
			)
			(placement
				(enabled no)
				(sheetname "")
			)
			(fill
				(thermal_gap 0.5)
				(thermal_bridge_width 0.5)
				(island_removal_mode 0)
			)
			(polygon
				(pts
					(xy 57.0357 -230.6955) (xy 57.0357 -230.313992) (xy 57.542938 -230.313992) (xy 57.542938 -230.6955)
				)
			)
		)
		(zone
			(layer "F.Cu")
			(hatch none 0.5)
			(connect_pads
				(clearance 0)
			)
			(min_thickness 0.25)
			(keepout
				(tracks not_allowed)
				(vias allowed)
				(pads allowed)
				(copperpour not_allowed)
				(footprints allowed)
			)
			(placement
				(enabled no)
				(sheetname "")
			)
			(fill
				(thermal_gap 0.5)
				(thermal_bridge_width 0.5)
				(island_removal_mode 0)
			)
			(polygon
				(pts
					(xy 57.0357 -230.6955) (xy 57.0357 -230.313992) (xy 57.542938 -230.313992) (xy 57.542938 -230.6955)
				)
			)
		)
		(zone
			(layer "F.Cu")
			(hatch none 0.5)
			(connect_pads
				(clearance 0)
			)
			(min_thickness 0.25)
			(keepout
				(tracks not_allowed)
				(vias allowed)
				(pads allowed)
				(copperpour not_allowed)
				(footprints allowed)
			)
			(placement
				(enabled no)
				(sheetname "")
			)
			(fill
				(thermal_gap 0.5)
				(thermal_bridge_width 0.5)
				(island_removal_mode 0)
			)
			(polygon
				(pts
					(xy 58.027062 -230.6955) (xy 58.027062 -230.313992) (xy 58.5343 -230.313992) (xy 58.5343 -230.6955)
				)
			)
		)
		(zone
			(layer "F.Cu")
			(hatch none 0.5)
			(connect_pads
				(clearance 0)
			)
			(min_thickness 0.25)
			(keepout
				(tracks allowed)
				(vias not_allowed)
				(pads allowed)
				(copperpour not_allowed)
				(footprints allowed)
			)
			(placement
				(enabled no)
				(sheetname "")
			)
			(fill
				(thermal_gap 0.5)
				(thermal_bridge_width 0.5)
				(island_removal_mode 0)
			)
			(polygon
				(pts
					(xy 58.027062 -230.6955) (xy 58.027062 -230.313992) (xy 58.5343 -230.313992) (xy 58.5343 -230.6955)
				)
			)
		)
	)
	(footprint ""
		(layer "F.Cu")
		(at 42.3672 -116.2812 90)
		(property "Reference" "SR938"
			(at 0 0 90)
			(layer "F.SilkS")
			(hide yes)
			(effects
				(font
					(size 1.27 1.27)
				)
			)
		)
		(property "Value" "0R2J-2-GP"
			(at 0.064008 -3.993896 90)
			(unlocked yes)
			(layer "F.Fab")
			(hide yes)
			(effects
				(font
					(size 1.016 1.016)
					(thickness 0.1524)
				)
			)
		)
		(property "Device Type" "R402H16"
			(at 0.064008 -5.517896 90)
			(unlocked yes)
			(layer "F.Fab")
			(hide yes)
			(effects
				(font
					(size 1.016 1.016)
					(thickness 0.1524)
				)
			)
		)
		(duplicate_pad_numbers_are_jumpers no)
		(fp_line
			(start 0.508 -0.9398)
			(end -0.508 -0.9398)
			(stroke
				(width 0.1524)
				(type default)
			)
			(layer "F.SilkS")
		)
		(fp_line
			(start -0.508 -0.9398)
			(end -0.508 0.9398)
			(stroke
				(width 0.1524)
				(type default)
			)
			(layer "F.SilkS")
		)
		(fp_rect
			(start -0.508 0.9398)
			(end 0.508 -0.9398)
			(stroke
				(width 0)
				(type default)
			)
			(fill no)
			(layer "F.CrtYd")
		)
		(fp_rect
			(start -0.508 0.9398)
			(end 0.508 -0.9398)
			(stroke
				(width 0)
				(type default)
			)
			(fill no)
			(layer "F.Fab")
		)
		(pad "1" smd custom
			(at 0 -0.4445 90)
			(size 0.1397 0.1397)
			(layers "F.Cu" "F.Mask" "F.Paste")
			(net "SAS_SDBTX")
			(options
				(clearance outline)
				(anchor circle)
			)
			(primitives
				(gr_poly
					(pts
						(arc
							(start -0.1778 -0.2794)
							(mid -0.249642 -0.249642)
							(end -0.2794 -0.1778)
						)
						(arc
							(start -0.2794 0.1778)
							(mid -0.249642 0.249642)
							(end -0.1778 0.2794)
						)
						(arc
							(start 0.1778 0.2794)
							(mid 0.249642 0.249642)
							(end 0.2794 0.1778)
						)
						(arc
							(start 0.2794 -0.1778)
							(mid 0.249642 -0.249642)
							(end 0.1778 -0.2794)
						)
					)
					(width 0)
					(fill yes)
				)
			)
		)
		(pad "2" smd custom
			(at 0 0.4445 90)
			(size 0.1397 0.1397)
			(layers "F.Cu" "F.Mask" "F.Paste")
			(net "SAS_R_SDBTX")
			(options
				(clearance outline)
				(anchor circle)
			)
			(primitives
				(gr_poly
					(pts
						(arc
							(start -0.1778 -0.2794)
							(mid -0.249642 -0.249642)
							(end -0.2794 -0.1778)
						)
						(arc
							(start -0.2794 0.1778)
							(mid -0.249642 0.249642)
							(end -0.1778 0.2794)
						)
						(arc
							(start 0.1778 0.2794)
							(mid 0.249642 0.249642)
							(end 0.2794 0.1778)
						)
						(arc
							(start 0.2794 -0.1778)
							(mid 0.249642 -0.249642)
							(end 0.1778 -0.2794)
						)
					)
					(width 0)
					(fill yes)
				)
			)
		)
	)
	(footprint ""
		(layer "F.Cu")
		(at 320.9798 -119.4308 180)
		(property "Reference" "PR19"
			(at 0 0 180)
			(layer "F.SilkS")
			(hide yes)
			(effects
				(font
					(size 1.27 1.27)
				)
			)
		)
		(property "Value" "2D2R3J-2-GP"
			(at -0.0254 -2.5146 180)
			(unlocked yes)
			(layer "F.Fab")
			(hide yes)
			(effects
				(font
					(size 1.016 1.016)
					(thickness 0.1524)
				)
			)
		)
		(property "Device Type" "R603H22"
			(at -0.0254 -4.0386 180)
			(unlocked yes)
			(layer "F.Fab")
			(hide yes)
			(effects
				(font
					(size 1.016 1.016)
					(thickness 0.1524)
				)
			)
		)
		(duplicate_pad_numbers_are_jumpers no)
		(fp_line
			(start 0.2032 0)
			(end 0.4826 0)
			(stroke
				(width 0.2032)
				(type default)
			)
			(layer "F.SilkS")
		)
		(fp_line
			(start -0.4826 0)
			(end -0.2032 0)
			(stroke
				(width 0.2032)
				(type default)
			)
			(layer "F.SilkS")
		)
		(fp_rect
			(start -0.5842 1.3335)
			(end 0.5842 -1.3335)
			(stroke
				(width 0)
				(type default)
			)
			(fill no)
			(layer "F.CrtYd")
		)
		(fp_rect
			(start -0.5842 1.3335)
			(end 0.5842 -1.3335)
			(stroke
				(width 0)
				(type default)
			)
			(fill no)
			(layer "F.Fab")
		)
		(pad "1" smd custom
			(at 0 -0.762 180)
			(size 0.2159 0.2159)
			(layers "F.Cu" "F.Mask" "F.Paste")
			(net "P3V3_STBY_VDD")
			(options
				(clearance outline)
				(anchor circle)
			)
			(primitives
				(gr_poly
					(pts
						(arc
							(start -0.3302 -0.4318)
							(mid -0.402042 -0.402042)
							(end -0.4318 -0.3302)
						)
						(arc
							(start -0.4318 0.3302)
							(mid -0.402042 0.402042)
							(end -0.3302 0.4318)
						)
						(arc
							(start 0.3302 0.4318)
							(mid 0.402042 0.402042)
							(end 0.4318 0.3302)
						)
						(arc
							(start 0.4318 -0.3302)
							(mid 0.402042 -0.402042)
							(end 0.3302 -0.4318)
						)
					)
					(width 0)
					(fill yes)
				)
			)
		)
		(pad "2" smd custom
			(at 0 0.762 180)
			(size 0.2159 0.2159)
			(layers "F.Cu" "F.Mask" "F.Paste")
			(net "P12V")
			(options
				(clearance outline)
				(anchor circle)
			)
			(primitives
				(gr_poly
					(pts
						(arc
							(start -0.3302 -0.4318)
							(mid -0.402042 -0.402042)
							(end -0.4318 -0.3302)
						)
						(arc
							(start -0.4318 0.3302)
							(mid -0.402042 0.402042)
							(end -0.3302 0.4318)
						)
						(arc
							(start 0.3302 0.4318)
							(mid 0.402042 0.402042)
							(end 0.4318 0.3302)
						)
						(arc
							(start 0.4318 -0.3302)
							(mid 0.402042 -0.402042)
							(end 0.3302 -0.4318)
						)
					)
					(width 0)
					(fill yes)
				)
			)
		)
	)
)
